# T6G (Grand Teton) — schematic netlist excerpt (pin names and nets, part order shuffled) for the footprints in the layout excerpt that follows; sources: Cadence DE-HDL packaged netlist, KiCad conversion of 04192023_DAF0TMB3IC0_F0TG_MB_C_brd_V02_OCP.brd

PC6563  Q_CAP  100NF 50V 10% X7R  pkg C0402  page 363 : A = SW_P0V9_RETIMER_CPU0_BOOT1_RC ; B = SW_P0V9_RETIMER_CPU0_PH1
PR3947  Q_RES  2.8K 1% CHIP  pkg 0402LF  page 147 : A = GND ; B = P3V3_E1S_ILIMIT_0

(kicad_pcb
	(version 20260206)
	(generator "pcbnew")
	(generator_version "10.0")
	(general
		(thickness 1.6)
		(legacy_teardrops no)
	)
	(paper "A4")
	(title_block
		(title "04192023_DAF0TMB3IC0_F0TG_MB_C_brd_V02_OCP.brd")
		(comment 1 "Grand Teton / footprints 958-960 of 8354")
	)
	(layers
		(0 "F.Cu" signal "TOP")
		(4 "In1.Cu" signal "GND")
		(6 "In2.Cu" signal "IN1")
		(8 "In3.Cu" signal "GND1")
		(10 "In4.Cu" signal "IN2")
		(12 "In5.Cu" signal "GND2")
		(14 "In6.Cu" signal "IN3")
		(16 "In7.Cu" signal "GND3")
		(18 "In8.Cu" signal "VCC")
		(20 "In9.Cu" signal "VCC1")
		(22 "In10.Cu" signal "GND4")
		(24 "In11.Cu" signal "IN4")
		(26 "In12.Cu" signal "GND5")
		(28 "In13.Cu" signal "IN5")
		(30 "In14.Cu" signal "GND6")
		(32 "In15.Cu" signal "IN6")
		(34 "In16.Cu" signal "GND7")
		(2 "B.Cu" signal "BOTTOM")
		(9 "F.Adhes" user "F.Adhesive")
		(11 "B.Adhes" user "B.Adhesive")
		(13 "F.Paste" user "Package Geometry/Pastemask Top")
		(15 "B.Paste" user "Package Geometry/Pastemask Bottom")
		(5 "F.SilkS" user "Ref Des/Silkscreen Top")
		(7 "B.SilkS" user "Ref Des/Silkscreen Bottom")
		(1 "F.Mask" user "Board Geometry/Soldermask Top")
		(3 "B.Mask" user "Board Geometry/Soldermask Bottom")
		(17 "Dwgs.User" user "User.Drawings")
		(19 "Cmts.User" user "User.Comments")
		(21 "Eco1.User" user "User.Eco1")
		(23 "Eco2.User" user "User.Eco2")
		(25 "Edge.Cuts" user "Board Geometry/Outline")
		(27 "Margin" user)
		(31 "F.CrtYd" user "Package Geometry/Place Bound Top")
		(29 "B.CrtYd" user "Package Geometry/Place Bound Bottom")
		(35 "F.Fab" user "Ref Des/Assembly Top")
		(33 "B.Fab" user "Ref Des/Assembly Bottom")
	)
	(footprint ""
		(layer "F.Cu")
		(at 447.052954 -401.785328 -90)
		(property "Reference" "PC6563"
			(at 0 0 270)
			(layer "F.SilkS")
			(hide yes)
			(effects
				(font
					(size 1.27 1.27)
				)
			)
		)
		(property "Value" ""
			(at 0 0 270)
			(layer "F.Fab")
			(effects
				(font
					(size 1.27 1.27)
				)
			)
		)
		(duplicate_pad_numbers_are_jumpers no)
		(fp_line
			(start -0.7874 0.4064)
			(end -0.7874 -0.4064)
			(stroke
				(width 0.1524)
				(type default)
			)
			(layer "F.SilkS")
		)
		(fp_line
			(start 0.7874 0.4064)
			(end -0.7874 0.4064)
			(stroke
				(width 0.1524)
				(type default)
			)
			(layer "F.SilkS")
		)
		(fp_line
			(start -0.7874 -0.4064)
			(end 0.7874 -0.4064)
			(stroke
				(width 0.1524)
				(type default)
			)
			(layer "F.SilkS")
		)
		(fp_line
			(start 0.7874 -0.4064)
			(end 0.7874 0.4064)
			(stroke
				(width 0.1524)
				(type default)
			)
			(layer "F.SilkS")
		)
		(fp_line
			(start -0.67945 0.3048)
			(end -0.67945 -0.305054)
			(stroke
				(width 0.1)
				(type default)
			)
			(layer "F.Fab")
		)
		(fp_line
			(start -0.12065 0.3048)
			(end -0.67945 0.3048)
			(stroke
				(width 0.1)
				(type default)
			)
			(layer "F.Fab")
		)
		(fp_line
			(start 0.120396 0.3048)
			(end 0.120396 0.2794)
			(stroke
				(width 0.1)
				(type default)
			)
			(layer "F.Fab")
		)
		(fp_line
			(start 0.67945 0.3048)
			(end 0.120396 0.3048)
			(stroke
				(width 0.1)
				(type default)
			)
			(layer "F.Fab")
		)
		(fp_line
			(start -0.12065 0.2794)
			(end -0.12065 0.3048)
			(stroke
				(width 0.1)
				(type default)
			)
			(layer "F.Fab")
		)
		(fp_line
			(start 0.120396 0.2794)
			(end -0.12065 0.2794)
			(stroke
				(width 0.1)
				(type default)
			)
			(layer "F.Fab")
		)
		(fp_line
			(start -0.12065 -0.2794)
			(end 0.12065 -0.2794)
			(stroke
				(width 0.1)
				(type default)
			)
			(layer "F.Fab")
		)
		(fp_line
			(start 0.12065 -0.2794)
			(end 0.12065 -0.3048)
			(stroke
				(width 0.1)
				(type default)
			)
			(layer "F.Fab")
		)
		(fp_line
			(start 0.12065 -0.3048)
			(end 0.67945 -0.3048)
			(stroke
				(width 0.1)
				(type default)
			)
			(layer "F.Fab")
		)
		(fp_line
			(start 0.67945 -0.3048)
			(end 0.67945 0.3048)
			(stroke
				(width 0.1)
				(type default)
			)
			(layer "F.Fab")
		)
		(fp_line
			(start -0.67945 -0.305054)
			(end -0.12065 -0.305054)
			(stroke
				(width 0.1)
				(type default)
			)
			(layer "F.Fab")
		)
		(fp_line
			(start -0.12065 -0.305054)
			(end -0.12065 -0.2794)
			(stroke
				(width 0.1)
				(type default)
			)
			(layer "F.Fab")
		)
		(pad "1" smd circle
			(at -0.40005 0 270)
			(size 0 0)
			(layers "F.Cu" "F.Mask" "F.Paste")
			(net "SW_P0V9_RETIMER_CPU0_BOOT1_RC")
		)
		(pad "2" smd circle
			(at 0.40005 0 270)
			(size 0 0)
			(layers "F.Cu" "F.Mask" "F.Paste")
			(net "SW_P0V9_RETIMER_CPU0_PH1")
		)
	)
	(footprint ""
		(layer "F.Cu")
		(at 219.61475 -347.604588 180)
		(property "Reference" ""
			(at 0 0 180)
			(layer "F.SilkS")
			(hide yes)
			(effects
				(font
					(size 1.27 1.27)
				)
			)
		)
		(property "Value" ""
			(at 0 0 180)
			(layer "F.Fab")
			(effects
				(font
					(size 1.27 1.27)
				)
			)
		)
		(duplicate_pad_numbers_are_jumpers no)
		(pad "1" smd circle
			(at 0 0 180)
			(size 0.9906 0.9906)
			(layers "F.Cu" "F.Mask" "F.Paste")
			(net "Net_48")
		)
		(zone
			(layer "F.Cu")
			(hatch none 0.5)
			(connect_pads
				(clearance 0)
			)
			(min_thickness 0.25)
			(keepout
				(tracks not_allowed)
				(vias allowed)
				(pads allowed)
				(copperpour not_allowed)
				(footprints allowed)
			)
			(placement
				(enabled no)
				(sheetname "")
			)
			(fill
				(thermal_gap 0.5)
				(thermal_bridge_width 0.5)
				(island_removal_mode 0)
			)
			(polygon
				(pts
					(arc
						(start 221.24035 -347.604588)
						(mid 217.98915 -347.604588)
						(end 221.24035 -347.604588)
					)
				)
			)
		)
	)
	(footprint ""
		(layer "F.Cu")
		(at 192.599818 -70.185788)
		(property "Reference" "PR3947"
			(at 0 0 0)
			(layer "F.SilkS")
			(hide yes)
			(effects
				(font
					(size 1.27 1.27)
				)
			)
		)
		(property "Value" ""
			(at 0 0 0)
			(layer "F.Fab")
			(effects
				(font
					(size 1.27 1.27)
				)
			)
		)
		(duplicate_pad_numbers_are_jumpers no)
		(fp_line
			(start -0.7874 -0.4064)
			(end 0.7874 -0.4064)
			(stroke
				(width 0.1524)
				(type default)
			)
			(layer "F.SilkS")
		)
		(fp_line
			(start -0.7874 0.4064)
			(end -0.7874 -0.4064)
			(stroke
				(width 0.1524)
				(type default)
			)
			(layer "F.SilkS")
		)
		(fp_line
			(start 0.7874 -0.4064)
			(end 0.7874 0.4064)
			(stroke
				(width 0.1524)
				(type default)
			)
			(layer "F.SilkS")
		)
		(fp_line
			(start 0.7874 0.4064)
			(end -0.7874 0.4064)
			(stroke
				(width 0.1524)
				(type default)
			)
			(layer "F.SilkS")
		)
		(fp_line
			(start -0.67945 -0.305054)
			(end -0.12065 -0.305054)
			(stroke
				(width 0.1)
				(type default)
			)
			(layer "F.Fab")
		)
		(fp_line
			(start -0.67945 0.3048)
			(end -0.67945 -0.305054)
			(stroke
				(width 0.1)
				(type default)
			)
			(layer "F.Fab")
		)
		(fp_line
			(start -0.12065 -0.305054)
			(end -0.12065 -0.2794)
			(stroke
				(width 0.1)
				(type default)
			)
			(layer "F.Fab")
		)
		(fp_line
			(start -0.12065 -0.2794)
			(end 0.12065 -0.2794)
			(stroke
				(width 0.1)
				(type default)
			)
			(layer "F.Fab")
		)
		(fp_line
			(start -0.12065 0.2794)
			(end -0.12065 0.3048)
			(stroke
				(width 0.1)
				(type default)
			)
			(layer "F.Fab")
		)
		(fp_line
			(start -0.12065 0.3048)
			(end -0.67945 0.3048)
			(stroke
				(width 0.1)
				(type default)
			)
			(layer "F.Fab")
		)
		(fp_line
			(start 0.120396 0.2794)
			(end -0.12065 0.2794)
			(stroke
				(width 0.1)
				(type default)
			)
			(layer "F.Fab")
		)
		(fp_line
			(start 0.120396 0.3048)
			(end 0.120396 0.2794)
			(stroke
				(width 0.1)
				(type default)
			)
			(layer "F.Fab")
		)
		(fp_line
			(start 0.12065 -0.3048)
			(end 0.67945 -0.3048)
			(stroke
				(width 0.1)
				(type default)
			)
			(layer "F.Fab")
		)
		(fp_line
			(start 0.12065 -0.2794)
			(end 0.12065 -0.3048)
			(stroke
				(width 0.1)
				(type default)
			)
			(layer "F.Fab")
		)
		(fp_line
			(start 0.67945 -0.3048)
			(end 0.67945 0.3048)
			(stroke
				(width 0.1)
				(type default)
			)
			(layer "F.Fab")
		)
		(fp_line
			(start 0.67945 0.3048)
			(end 0.120396 0.3048)
			(stroke
				(width 0.1)
				(type default)
			)
			(layer "F.Fab")
		)
		(pad "1" smd circle
			(at -0.40005 0)
			(size 0 0)
			(layers "F.Cu" "F.Mask" "F.Paste")
			(net "GND")
		)
		(pad "2" smd circle
			(at 0.40005 0)
			(size 0 0)
			(layers "F.Cu" "F.Mask" "F.Paste")
			(net "P3V3_E1S_ILIMIT_0")
		)
	)
)
